(kicad_pcb
	(version 20260206)
	(generator "pcbnew")
	(generator_version "10.0")
	(general
		(thickness 1.6)
		(legacy_teardrops no)
	)
	(paper "A4")
	(title_block
		(title "04192023_DAF0TMB3IC0_F0TG_MB_C_brd_V02_OCP.brd")
		(comment 1 "Grand Teton / footprints 2631-2637 of 8354")
	)
	(layers
		(0 "F.Cu" signal "TOP")
		(4 "In1.Cu" signal "GND")
		(6 "In2.Cu" signal "IN1")
		(8 "In3.Cu" signal "GND1")
		(10 "In4.Cu" signal "IN2")
		(12 "In5.Cu" signal "GND2")
		(14 "In6.Cu" signal "IN3")
		(16 "In7.Cu" signal "GND3")
		(18 "In8.Cu" signal "VCC")
		(20 "In9.Cu" signal "VCC1")
		(22 "In10.Cu" signal "GND4")
		(24 "In11.Cu" signal "IN4")
		(26 "In12.Cu" signal "GND5")
		(28 "In13.Cu" signal "IN5")
		(30 "In14.Cu" signal "GND6")
		(32 "In15.Cu" signal "IN6")
		(34 "In16.Cu" signal "GND7")
		(2 "B.Cu" signal "BOTTOM")
		(9 "F.Adhes" user "F.Adhesive")
		(11 "B.Adhes" user "B.Adhesive")
		(13 "F.Paste" user "Package Geometry/Pastemask Top")
		(15 "B.Paste" user "Package Geometry/Pastemask Bottom")
		(5 "F.SilkS" user "Ref Des/Silkscreen Top")
		(7 "B.SilkS" user "Ref Des/Silkscreen Bottom")
		(1 "F.Mask" user "Board Geometry/Soldermask Top")
		(3 "B.Mask" user "Board Geometry/Soldermask Bottom")
		(17 "Dwgs.User" user "User.Drawings")
		(19 "Cmts.User" user "User.Comments")
		(21 "Eco1.User" user "User.Eco1")
		(23 "Eco2.User" user "User.Eco2")
		(25 "Edge.Cuts" user "Board Geometry/Outline")
		(27 "Margin" user)
		(31 "F.CrtYd" user "Package Geometry/Place Bound Top")
		(29 "B.CrtYd" user "Package Geometry/Place Bound Bottom")
		(35 "F.Fab" user "Ref Des/Assembly Top")
		(33 "B.Fab" user "Ref Des/Assembly Bottom")
	)
	(footprint ""
		(layer "F.Cu")
		(at 400.31924 -378.95403 -90)
		(property "Reference" "C863"
			(at 0 0 270)
			(layer "F.SilkS")
			(hide yes)
			(effects
				(font
					(size 1.27 1.27)
				)
			)
		)
		(property "Value" ""
			(at 0 0 270)
			(layer "F.Fab")
			(effects
				(font
					(size 1.27 1.27)
				)
			)
		)
		(duplicate_pad_numbers_are_jumpers no)
		(fp_line
			(start -0.299974 0.150114)
			(end -0.299974 -0.150114)
			(stroke
				(width 0.1)
				(type default)
			)
			(layer "F.Fab")
		)
		(fp_line
			(start 0.299974 0.150114)
			(end -0.299974 0.150114)
			(stroke
				(width 0.1)
				(type default)
			)
			(layer "F.Fab")
		)
		(fp_line
			(start -0.299974 -0.150114)
			(end 0.299974 -0.150114)
			(stroke
				(width 0.1)
				(type default)
			)
			(layer "F.Fab")
		)
		(fp_line
			(start 0.299974 -0.150114)
			(end 0.299974 0.150114)
			(stroke
				(width 0.1)
				(type default)
			)
			(layer "F.Fab")
		)
		(pad "1" smd rect
			(at -0.2667 0 270)
			(size 0.3048 0.381)
			(layers "F.Cu" "F.Mask" "F.Paste")
			(net "P5E_CPU0_P2_TX_C_DP<3>")
		)
		(pad "2" smd rect
			(at 0.2667 0 270)
			(size 0.3048 0.381)
			(layers "F.Cu" "F.Mask" "F.Paste")
			(net "P5E_CPU0_P2_TX_DP<3>")
		)
	)
	(footprint ""
		(layer "F.Cu")
		(at 254.11684 -92.719144 -90)
		(property "Reference" "R1638"
			(at 0 0 270)
			(layer "F.SilkS")
			(hide yes)
			(effects
				(font
					(size 1.27 1.27)
				)
			)
		)
		(property "Value" ""
			(at 0 0 270)
			(layer "F.Fab")
			(effects
				(font
					(size 1.27 1.27)
				)
			)
		)
		(duplicate_pad_numbers_are_jumpers no)
		(fp_line
			(start -0.7874 0.4064)
			(end -0.7874 -0.4064)
			(stroke
				(width 0.1524)
				(type default)
			)
			(layer "F.SilkS")
		)
		(fp_line
			(start 0.7874 0.4064)
			(end -0.7874 0.4064)
			(stroke
				(width 0.1524)
				(type default)
			)
			(layer "F.SilkS")
		)
		(fp_line
			(start -0.7874 -0.4064)
			(end 0.7874 -0.4064)
			(stroke
				(width 0.1524)
				(type default)
			)
			(layer "F.SilkS")
		)
		(fp_line
			(start 0.7874 -0.4064)
			(end 0.7874 0.4064)
			(stroke
				(width 0.1524)
				(type default)
			)
			(layer "F.SilkS")
		)
		(fp_line
			(start -0.67945 0.3048)
			(end -0.67945 -0.305054)
			(stroke
				(width 0.1)
				(type default)
			)
			(layer "F.Fab")
		)
		(fp_line
			(start -0.12065 0.3048)
			(end -0.67945 0.3048)
			(stroke
				(width 0.1)
				(type default)
			)
			(layer "F.Fab")
		)
		(fp_line
			(start 0.120396 0.3048)
			(end 0.120396 0.2794)
			(stroke
				(width 0.1)
				(type default)
			)
			(layer "F.Fab")
		)
		(fp_line
			(start 0.67945 0.3048)
			(end 0.120396 0.3048)
			(stroke
				(width 0.1)
				(type default)
			)
			(layer "F.Fab")
		)
		(fp_line
			(start -0.12065 0.2794)
			(end -0.12065 0.3048)
			(stroke
				(width 0.1)
				(type default)
			)
			(layer "F.Fab")
		)
		(fp_line
			(start 0.120396 0.2794)
			(end -0.12065 0.2794)
			(stroke
				(width 0.1)
				(type default)
			)
			(layer "F.Fab")
		)
		(fp_line
			(start -0.12065 -0.2794)
			(end 0.12065 -0.2794)
			(stroke
				(width 0.1)
				(type default)
			)
			(layer "F.Fab")
		)
		(fp_line
			(start 0.12065 -0.2794)
			(end 0.12065 -0.3048)
			(stroke
				(width 0.1)
				(type default)
			)
			(layer "F.Fab")
		)
		(fp_line
			(start 0.12065 -0.3048)
			(end 0.67945 -0.3048)
			(stroke
				(width 0.1)
				(type default)
			)
			(layer "F.Fab")
		)
		(fp_line
			(start 0.67945 -0.3048)
			(end 0.67945 0.3048)
			(stroke
				(width 0.1)
				(type default)
			)
			(layer "F.Fab")
		)
		(fp_line
			(start -0.67945 -0.305054)
			(end -0.12065 -0.305054)
			(stroke
				(width 0.1)
				(type default)
			)
			(layer "F.Fab")
		)
		(fp_line
			(start -0.12065 -0.305054)
			(end -0.12065 -0.2794)
			(stroke
				(width 0.1)
				(type default)
			)
			(layer "F.Fab")
		)
		(pad "1" smd circle
			(at -0.40005 0 270)
			(size 0 0)
			(layers "F.Cu" "F.Mask" "F.Paste")
			(net "JTAG_P0_R_TCK")
		)
		(pad "2" smd circle
			(at 0.40005 0 270)
			(size 0 0)
			(layers "F.Cu" "F.Mask" "F.Paste")
			(net "JTAG_CPU0_TCK")
		)
	)
	(footprint ""
		(layer "F.Cu")
		(at 463.465926 -96.406208)
		(property "Reference" "R2474"
			(at 0 0 0)
			(layer "F.SilkS")
			(hide yes)
			(effects
				(font
					(size 1.27 1.27)
				)
			)
		)
		(property "Value" ""
			(at 0 0 0)
			(layer "F.Fab")
			(effects
				(font
					(size 1.27 1.27)
				)
			)
		)
		(duplicate_pad_numbers_are_jumpers no)
		(fp_line
			(start -0.7874 -0.4064)
			(end 0.7874 -0.4064)
			(stroke
				(width 0.1524)
				(type default)
			)
			(layer "F.SilkS")
		)
		(fp_line
			(start -0.7874 0.4064)
			(end -0.7874 -0.4064)
			(stroke
				(width 0.1524)
				(type default)
			)
			(layer "F.SilkS")
		)
		(fp_line
			(start 0.7874 -0.4064)
			(end 0.7874 0.4064)
			(stroke
				(width 0.1524)
				(type default)
			)
			(layer "F.SilkS")
		)
		(fp_line
			(start 0.7874 0.4064)
			(end -0.7874 0.4064)
			(stroke
				(width 0.1524)
				(type default)
			)
			(layer "F.SilkS")
		)
		(fp_line
			(start -0.67945 -0.305054)
			(end -0.12065 -0.305054)
			(stroke
				(width 0.1)
				(type default)
			)
			(layer "F.Fab")
		)
		(fp_line
			(start -0.67945 0.3048)
			(end -0.67945 -0.305054)
			(stroke
				(width 0.1)
				(type default)
			)
			(layer "F.Fab")
		)
		(fp_line
			(start -0.12065 -0.305054)
			(end -0.12065 -0.2794)
			(stroke
				(width 0.1)
				(type default)
			)
			(layer "F.Fab")
		)
		(fp_line
			(start -0.12065 -0.2794)
			(end 0.12065 -0.2794)
			(stroke
				(width 0.1)
				(type default)
			)
			(layer "F.Fab")
		)
		(fp_line
			(start -0.12065 0.2794)
			(end -0.12065 0.3048)
			(stroke
				(width 0.1)
				(type default)
			)
			(layer "F.Fab")
		)
		(fp_line
			(start -0.12065 0.3048)
			(end -0.67945 0.3048)
			(stroke
				(width 0.1)
				(type default)
			)
			(layer "F.Fab")
		)
		(fp_line
			(start 0.120396 0.2794)
			(end -0.12065 0.2794)
			(stroke
				(width 0.1)
				(type default)
			)
			(layer "F.Fab")
		)
		(fp_line
			(start 0.120396 0.3048)
			(end 0.120396 0.2794)
			(stroke
				(width 0.1)
				(type default)
			)
			(layer "F.Fab")
		)
		(fp_line
			(start 0.12065 -0.3048)
			(end 0.67945 -0.3048)
			(stroke
				(width 0.1)
				(type default)
			)
			(layer "F.Fab")
		)
		(fp_line
			(start 0.12065 -0.2794)
			(end 0.12065 -0.3048)
			(stroke
				(width 0.1)
				(type default)
			)
			(layer "F.Fab")
		)
		(fp_line
			(start 0.67945 -0.3048)
			(end 0.67945 0.3048)
			(stroke
				(width 0.1)
				(type default)
			)
			(layer "F.Fab")
		)
		(fp_line
			(start 0.67945 0.3048)
			(end 0.120396 0.3048)
			(stroke
				(width 0.1)
				(type default)
			)
			(layer "F.Fab")
		)
		(pad "1" smd circle
			(at -0.40005 0)
			(size 0 0)
			(layers "F.Cu" "F.Mask" "F.Paste")
			(net "FM_NCSI_OCP_SFF_R_OE")
		)
		(pad "2" smd circle
			(at 0.40005 0)
			(size 0 0)
			(layers "F.Cu" "F.Mask" "F.Paste")
			(net "FB_BMC_ISOLATE")
		)
	)
	(footprint ""
		(layer "F.Cu")
		(at 462.20507 -42.004488 90)
		(property "Reference" "R4070"
			(at 0 0 90)
			(layer "F.SilkS")
			(hide yes)
			(effects
				(font
					(size 1.27 1.27)
				)
			)
		)
		(property "Value" ""
			(at 0 0 90)
			(layer "F.Fab")
			(effects
				(font
					(size 1.27 1.27)
				)
			)
		)
		(duplicate_pad_numbers_are_jumpers no)
		(fp_line
			(start 0.7874 -0.4064)
			(end 0.7874 0.4064)
			(stroke
				(width 0.1524)
				(type default)
			)
			(layer "F.SilkS")
		)
		(fp_line
			(start -0.7874 -0.4064)
			(end 0.7874 -0.4064)
			(stroke
				(width 0.1524)
				(type default)
			)
			(layer "F.SilkS")
		)
		(fp_line
			(start 0.7874 0.4064)
			(end -0.7874 0.4064)
			(stroke
				(width 0.1524)
				(type default)
			)
			(layer "F.SilkS")
		)
		(fp_line
			(start -0.7874 0.4064)
			(end -0.7874 -0.4064)
			(stroke
				(width 0.1524)
				(type default)
			)
			(layer "F.SilkS")
		)
		(fp_line
			(start -0.12065 -0.305054)
			(end -0.12065 -0.2794)
			(stroke
				(width 0.1)
				(type default)
			)
			(layer "F.Fab")
		)
		(fp_line
			(start -0.67945 -0.305054)
			(end -0.12065 -0.305054)
			(stroke
				(width 0.1)
				(type default)
			)
			(layer "F.Fab")
		)
		(fp_line
			(start 0.67945 -0.3048)
			(end 0.67945 0.3048)
			(stroke
				(width 0.1)
				(type default)
			)
			(layer "F.Fab")
		)
		(fp_line
			(start 0.12065 -0.3048)
			(end 0.67945 -0.3048)
			(stroke
				(width 0.1)
				(type default)
			)
			(layer "F.Fab")
		)
		(fp_line
			(start 0.12065 -0.2794)
			(end 0.12065 -0.3048)
			(stroke
				(width 0.1)
				(type default)
			)
			(layer "F.Fab")
		)
		(fp_line
			(start -0.12065 -0.2794)
			(end 0.12065 -0.2794)
			(stroke
				(width 0.1)
				(type default)
			)
			(layer "F.Fab")
		)
		(fp_line
			(start 0.120396 0.2794)
			(end -0.12065 0.2794)
			(stroke
				(width 0.1)
				(type default)
			)
			(layer "F.Fab")
		)
		(fp_line
			(start -0.12065 0.2794)
			(end -0.12065 0.3048)
			(stroke
				(width 0.1)
				(type default)
			)
			(layer "F.Fab")
		)
		(fp_line
			(start 0.67945 0.3048)
			(end 0.120396 0.3048)
			(stroke
				(width 0.1)
				(type default)
			)
			(layer "F.Fab")
		)
		(fp_line
			(start 0.120396 0.3048)
			(end 0.120396 0.2794)
			(stroke
				(width 0.1)
				(type default)
			)
			(layer "F.Fab")
		)
		(fp_line
			(start -0.12065 0.3048)
			(end -0.67945 0.3048)
			(stroke
				(width 0.1)
				(type default)
			)
			(layer "F.Fab")
		)
		(fp_line
			(start -0.67945 0.3048)
			(end -0.67945 -0.305054)
			(stroke
				(width 0.1)
				(type default)
			)
			(layer "F.Fab")
		)
		(pad "1" smd circle
			(at -0.40005 0 90)
			(size 0 0)
			(layers "F.Cu" "F.Mask" "F.Paste")
			(net "P12V_AUX")
		)
		(pad "2" smd circle
			(at 0.40005 0 90)
			(size 0 0)
			(layers "F.Cu" "F.Mask" "F.Paste")
			(net "P3V3_OCP_1_EN_G")
		)
	)
	(footprint ""
		(layer "F.Cu")
		(at 358.727502 -164.638482 -90)
		(property "Reference" "PC566_5"
			(at 0 0 270)
			(layer "F.SilkS")
			(hide yes)
			(effects
				(font
					(size 1.27 1.27)
				)
			)
		)
		(property "Value" ""
			(at 0 0 270)
			(layer "F.Fab")
			(effects
				(font
					(size 1.27 1.27)
				)
			)
		)
		(duplicate_pad_numbers_are_jumpers no)
		(fp_line
			(start -0.7874 0.4064)
			(end -0.7874 -0.4064)
			(stroke
				(width 0.1524)
				(type default)
			)
			(layer "F.SilkS")
		)
		(fp_line
			(start 0.7874 0.4064)
			(end -0.7874 0.4064)
			(stroke
				(width 0.1524)
				(type default)
			)
			(layer "F.SilkS")
		)
		(fp_line
			(start -0.7874 -0.4064)
			(end 0.7874 -0.4064)
			(stroke
				(width 0.1524)
				(type default)
			)
			(layer "F.SilkS")
		)
		(fp_line
			(start 0.7874 -0.4064)
			(end 0.7874 0.4064)
			(stroke
				(width 0.1524)
				(type default)
			)
			(layer "F.SilkS")
		)
		(fp_line
			(start -0.67945 0.3048)
			(end -0.67945 -0.305054)
			(stroke
				(width 0.1)
				(type default)
			)
			(layer "F.Fab")
		)
		(fp_line
			(start -0.12065 0.3048)
			(end -0.67945 0.3048)
			(stroke
				(width 0.1)
				(type default)
			)
			(layer "F.Fab")
		)
		(fp_line
			(start 0.120396 0.3048)
			(end 0.120396 0.2794)
			(stroke
				(width 0.1)
				(type default)
			)
			(layer "F.Fab")
		)
		(fp_line
			(start 0.67945 0.3048)
			(end 0.120396 0.3048)
			(stroke
				(width 0.1)
				(type default)
			)
			(layer "F.Fab")
		)
		(fp_line
			(start -0.12065 0.2794)
			(end -0.12065 0.3048)
			(stroke
				(width 0.1)
				(type default)
			)
			(layer "F.Fab")
		)
		(fp_line
			(start 0.120396 0.2794)
			(end -0.12065 0.2794)
			(stroke
				(width 0.1)
				(type default)
			)
			(layer "F.Fab")
		)
		(fp_line
			(start -0.12065 -0.2794)
			(end 0.12065 -0.2794)
			(stroke
				(width 0.1)
				(type default)
			)
			(layer "F.Fab")
		)
		(fp_line
			(start 0.12065 -0.2794)
			(end 0.12065 -0.3048)
			(stroke
				(width 0.1)
				(type default)
			)
			(layer "F.Fab")
		)
		(fp_line
			(start 0.12065 -0.3048)
			(end 0.67945 -0.3048)
			(stroke
				(width 0.1)
				(type default)
			)
			(layer "F.Fab")
		)
		(fp_line
			(start 0.67945 -0.3048)
			(end 0.67945 0.3048)
			(stroke
				(width 0.1)
				(type default)
			)
			(layer "F.Fab")
		)
		(fp_line
			(start -0.67945 -0.305054)
			(end -0.12065 -0.305054)
			(stroke
				(width 0.1)
				(type default)
			)
			(layer "F.Fab")
		)
		(fp_line
			(start -0.12065 -0.305054)
			(end -0.12065 -0.2794)
			(stroke
				(width 0.1)
				(type default)
			)
			(layer "F.Fab")
		)
		(pad "1" smd circle
			(at -0.40005 0 270)
			(size 0 0)
			(layers "F.Cu" "F.Mask" "F.Paste")
			(net "PVDDCR_CPU0_P0_VCCS")
		)
		(pad "2" smd circle
			(at 0.40005 0 270)
			(size 0 0)
			(layers "F.Cu" "F.Mask" "F.Paste")
			(net "GND")
		)
	)
	(footprint ""
		(layer "F.Cu")
		(at 38.0746 -437.226964 -90)
		(property "Reference" "R2910"
			(at 0 0 270)
			(layer "F.SilkS")
			(hide yes)
			(effects
				(font
					(size 1.27 1.27)
				)
			)
		)
		(property "Value" ""
			(at 0 0 270)
			(layer "F.Fab")
			(effects
				(font
					(size 1.27 1.27)
				)
			)
		)
		(duplicate_pad_numbers_are_jumpers no)
		(fp_line
			(start -0.7874 0.4064)
			(end -0.7874 -0.4064)
			(stroke
				(width 0.1524)
				(type default)
			)
			(layer "F.SilkS")
		)
		(fp_line
			(start 0.7874 0.4064)
			(end -0.7874 0.4064)
			(stroke
				(width 0.1524)
				(type default)
			)
			(layer "F.SilkS")
		)
		(fp_line
			(start -0.7874 -0.4064)
			(end 0.7874 -0.4064)
			(stroke
				(width 0.1524)
				(type default)
			)
			(layer "F.SilkS")
		)
		(fp_line
			(start 0.7874 -0.4064)
			(end 0.7874 0.4064)
			(stroke
				(width 0.1524)
				(type default)
			)
			(layer "F.SilkS")
		)
		(fp_line
			(start -0.67945 0.3048)
			(end -0.67945 -0.305054)
			(stroke
				(width 0.1)
				(type default)
			)
			(layer "F.Fab")
		)
		(fp_line
			(start -0.12065 0.3048)
			(end -0.67945 0.3048)
			(stroke
				(width 0.1)
				(type default)
			)
			(layer "F.Fab")
		)
		(fp_line
			(start 0.120396 0.3048)
			(end 0.120396 0.2794)
			(stroke
				(width 0.1)
				(type default)
			)
			(layer "F.Fab")
		)
		(fp_line
			(start 0.67945 0.3048)
			(end 0.120396 0.3048)
			(stroke
				(width 0.1)
				(type default)
			)
			(layer "F.Fab")
		)
		(fp_line
			(start -0.12065 0.2794)
			(end -0.12065 0.3048)
			(stroke
				(width 0.1)
				(type default)
			)
			(layer "F.Fab")
		)
		(fp_line
			(start 0.120396 0.2794)
			(end -0.12065 0.2794)
			(stroke
				(width 0.1)
				(type default)
			)
			(layer "F.Fab")
		)
		(fp_line
			(start -0.12065 -0.2794)
			(end 0.12065 -0.2794)
			(stroke
				(width 0.1)
				(type default)
			)
			(layer "F.Fab")
		)
		(fp_line
			(start 0.12065 -0.2794)
			(end 0.12065 -0.3048)
			(stroke
				(width 0.1)
				(type default)
			)
			(layer "F.Fab")
		)
		(fp_line
			(start 0.12065 -0.3048)
			(end 0.67945 -0.3048)
			(stroke
				(width 0.1)
				(type default)
			)
			(layer "F.Fab")
		)
		(fp_line
			(start 0.67945 -0.3048)
			(end 0.67945 0.3048)
			(stroke
				(width 0.1)
				(type default)
			)
			(layer "F.Fab")
		)
		(fp_line
			(start -0.67945 -0.305054)
			(end -0.12065 -0.305054)
			(stroke
				(width 0.1)
				(type default)
			)
			(layer "F.Fab")
		)
		(fp_line
			(start -0.12065 -0.305054)
			(end -0.12065 -0.2794)
			(stroke
				(width 0.1)
				(type default)
			)
			(layer "F.Fab")
		)
		(pad "1" smd circle
			(at -0.40005 0 270)
			(size 0 0)
			(layers "F.Cu" "F.Mask" "F.Paste")
			(net "P3V3_AUX")
		)
		(pad "2" smd circle
			(at 0.40005 0 270)
			(size 0 0)
			(layers "F.Cu" "F.Mask" "F.Paste")
			(net "FM_SWB_PWR_EN_R")
		)
	)
	(footprint ""
		(layer "F.Cu")
		(at 242.588542 -294.936926 180)
		(property "Reference" "PC6505"
			(at 0 0 180)
			(layer "F.SilkS")
			(hide yes)
			(effects
				(font
					(size 1.27 1.27)
				)
			)
		)
		(property "Value" ""
			(at 0 0 180)
			(layer "F.Fab")
			(effects
				(font
					(size 1.27 1.27)
				)
			)
		)
		(duplicate_pad_numbers_are_jumpers no)
		(fp_line
			(start 0.7874 0.4064)
			(end -0.7874 0.4064)
			(stroke
				(width 0.1524)
				(type default)
			)
			(layer "F.SilkS")
		)
		(fp_line
			(start 0.7874 -0.4064)
			(end 0.7874 0.4064)
			(stroke
				(width 0.1524)
				(type default)
			)
			(layer "F.SilkS")
		)
		(fp_line
			(start -0.7874 0.4064)
			(end -0.7874 -0.4064)
			(stroke
				(width 0.1524)
				(type default)
			)
			(layer "F.SilkS")
		)
		(fp_line
			(start -0.7874 -0.4064)
			(end 0.7874 -0.4064)
			(stroke
				(width 0.1524)
				(type default)
			)
			(layer "F.SilkS")
		)
		(fp_line
			(start 0.67945 0.3048)
			(end 0.120396 0.3048)
			(stroke
				(width 0.1)
				(type default)
			)
			(layer "F.Fab")
		)
		(fp_line
			(start 0.67945 -0.3048)
			(end 0.67945 0.3048)
			(stroke
				(width 0.1)
				(type default)
			)
			(layer "F.Fab")
		)
		(fp_line
			(start 0.12065 -0.2794)
			(end 0.12065 -0.3048)
			(stroke
				(width 0.1)
				(type default)
			)
			(layer "F.Fab")
		)
		(fp_line
			(start 0.12065 -0.3048)
			(end 0.67945 -0.3048)
			(stroke
				(width 0.1)
				(type default)
			)
			(layer "F.Fab")
		)
		(fp_line
			(start 0.120396 0.3048)
			(end 0.120396 0.2794)
			(stroke
				(width 0.1)
				(type default)
			)
			(layer "F.Fab")
		)
		(fp_line
			(start 0.120396 0.2794)
			(end -0.12065 0.2794)
			(stroke
				(width 0.1)
				(type default)
			)
			(layer "F.Fab")
		)
		(fp_line
			(start -0.12065 0.3048)
			(end -0.67945 0.3048)
			(stroke
				(width 0.1)
				(type default)
			)
			(layer "F.Fab")
		)
		(fp_line
			(start -0.12065 0.2794)
			(end -0.12065 0.3048)
			(stroke
				(width 0.1)
				(type default)
			)
			(layer "F.Fab")
		)
		(fp_line
			(start -0.12065 -0.2794)
			(end 0.12065 -0.2794)
			(stroke
				(width 0.1)
				(type default)
			)
			(layer "F.Fab")
		)
		(fp_line
			(start -0.12065 -0.305054)
			(end -0.12065 -0.2794)
			(stroke
				(width 0.1)
				(type default)
			)
			(layer "F.Fab")
		)
		(fp_line
			(start -0.67945 0.3048)
			(end -0.67945 -0.305054)
			(stroke
				(width 0.1)
				(type default)
			)
			(layer "F.Fab")
		)
		(fp_line
			(start -0.67945 -0.305054)
			(end -0.12065 -0.305054)
			(stroke
				(width 0.1)
				(type default)
			)
			(layer "F.Fab")
		)
		(pad "1" smd circle
			(at -0.40005 0 180)
			(size 0 0)
			(layers "F.Cu" "F.Mask" "F.Paste")
			(net "SW_P12V_AUX_P1V8_RETIMER_CPU0_FLT")
		)
		(pad "2" smd circle
			(at 0.40005 0 180)
			(size 0 0)
			(layers "F.Cu" "F.Mask" "F.Paste")
			(net "GND")
		)
	)
)
